(kicad_pcb
	(version 20260206)
	(generator "pcbnew")
	(generator_version "10.0")
	(general
		(thickness 1.6)
		(legacy_teardrops no)
	)
	(paper "A4")
	(title_block
		(title "04192023_DAF0TMB3IC0_F0TG_MB_C_brd_V02_OCP.brd")
		(comment 1 "Grand Teton / footprints 4684-4689 of 8354")
	)
	(layers
		(0 "F.Cu" signal "TOP")
		(4 "In1.Cu" signal "GND")
		(6 "In2.Cu" signal "IN1")
		(8 "In3.Cu" signal "GND1")
		(10 "In4.Cu" signal "IN2")
		(12 "In5.Cu" signal "GND2")
		(14 "In6.Cu" signal "IN3")
		(16 "In7.Cu" signal "GND3")
		(18 "In8.Cu" signal "VCC")
		(20 "In9.Cu" signal "VCC1")
		(22 "In10.Cu" signal "GND4")
		(24 "In11.Cu" signal "IN4")
		(26 "In12.Cu" signal "GND5")
		(28 "In13.Cu" signal "IN5")
		(30 "In14.Cu" signal "GND6")
		(32 "In15.Cu" signal "IN6")
		(34 "In16.Cu" signal "GND7")
		(2 "B.Cu" signal "BOTTOM")
		(9 "F.Adhes" user "F.Adhesive")
		(11 "B.Adhes" user "B.Adhesive")
		(13 "F.Paste" user "Package Geometry/Pastemask Top")
		(15 "B.Paste" user "Package Geometry/Pastemask Bottom")
		(5 "F.SilkS" user "Ref Des/Silkscreen Top")
		(7 "B.SilkS" user "Ref Des/Silkscreen Bottom")
		(1 "F.Mask" user "Board Geometry/Soldermask Top")
		(3 "B.Mask" user "Board Geometry/Soldermask Bottom")
		(17 "Dwgs.User" user "User.Drawings")
		(19 "Cmts.User" user "User.Comments")
		(21 "Eco1.User" user "User.Eco1")
		(23 "Eco2.User" user "User.Eco2")
		(25 "Edge.Cuts" user "Board Geometry/Outline")
		(27 "Margin" user)
		(31 "F.CrtYd" user "Package Geometry/Place Bound Top")
		(29 "B.CrtYd" user "Package Geometry/Place Bound Bottom")
		(35 "F.Fab" user "Ref Des/Assembly Top")
		(33 "B.Fab" user "Ref Des/Assembly Bottom")
	)
	(footprint ""
		(layer "F.Cu")
		(at 281.008582 -351.573846 90)
		(property "Reference" "PC175_9"
			(at 0 0 90)
			(layer "F.SilkS")
			(hide yes)
			(effects
				(font
					(size 1.27 1.27)
				)
			)
		)
		(property "Value" ""
			(at 0 0 90)
			(layer "F.Fab")
			(effects
				(font
					(size 1.27 1.27)
				)
			)
		)
		(duplicate_pad_numbers_are_jumpers no)
		(fp_line
			(start 0.7874 -0.4064)
			(end 0.7874 0.4064)
			(stroke
				(width 0.1524)
				(type default)
			)
			(layer "F.SilkS")
		)
		(fp_line
			(start -0.7874 -0.4064)
			(end 0.7874 -0.4064)
			(stroke
				(width 0.1524)
				(type default)
			)
			(layer "F.SilkS")
		)
		(fp_line
			(start 0.7874 0.4064)
			(end -0.7874 0.4064)
			(stroke
				(width 0.1524)
				(type default)
			)
			(layer "F.SilkS")
		)
		(fp_line
			(start -0.7874 0.4064)
			(end -0.7874 -0.4064)
			(stroke
				(width 0.1524)
				(type default)
			)
			(layer "F.SilkS")
		)
		(fp_line
			(start -0.12065 -0.305054)
			(end -0.12065 -0.2794)
			(stroke
				(width 0.1)
				(type default)
			)
			(layer "F.Fab")
		)
		(fp_line
			(start -0.67945 -0.305054)
			(end -0.12065 -0.305054)
			(stroke
				(width 0.1)
				(type default)
			)
			(layer "F.Fab")
		)
		(fp_line
			(start 0.67945 -0.3048)
			(end 0.67945 0.3048)
			(stroke
				(width 0.1)
				(type default)
			)
			(layer "F.Fab")
		)
		(fp_line
			(start 0.12065 -0.3048)
			(end 0.67945 -0.3048)
			(stroke
				(width 0.1)
				(type default)
			)
			(layer "F.Fab")
		)
		(fp_line
			(start 0.12065 -0.2794)
			(end 0.12065 -0.3048)
			(stroke
				(width 0.1)
				(type default)
			)
			(layer "F.Fab")
		)
		(fp_line
			(start -0.12065 -0.2794)
			(end 0.12065 -0.2794)
			(stroke
				(width 0.1)
				(type default)
			)
			(layer "F.Fab")
		)
		(fp_line
			(start 0.120396 0.2794)
			(end -0.12065 0.2794)
			(stroke
				(width 0.1)
				(type default)
			)
			(layer "F.Fab")
		)
		(fp_line
			(start -0.12065 0.2794)
			(end -0.12065 0.3048)
			(stroke
				(width 0.1)
				(type default)
			)
			(layer "F.Fab")
		)
		(fp_line
			(start 0.67945 0.3048)
			(end 0.120396 0.3048)
			(stroke
				(width 0.1)
				(type default)
			)
			(layer "F.Fab")
		)
		(fp_line
			(start 0.120396 0.3048)
			(end 0.120396 0.2794)
			(stroke
				(width 0.1)
				(type default)
			)
			(layer "F.Fab")
		)
		(fp_line
			(start -0.12065 0.3048)
			(end -0.67945 0.3048)
			(stroke
				(width 0.1)
				(type default)
			)
			(layer "F.Fab")
		)
		(fp_line
			(start -0.67945 0.3048)
			(end -0.67945 -0.305054)
			(stroke
				(width 0.1)
				(type default)
			)
			(layer "F.Fab")
		)
		(pad "1" smd circle
			(at -0.40005 0 90)
			(size 0 0)
			(layers "F.Cu" "F.Mask" "F.Paste")
			(net "PVDDCR_CPU1_P0_VCCS")
		)
		(pad "2" smd circle
			(at 0.40005 0 90)
			(size 0 0)
			(layers "F.Cu" "F.Mask" "F.Paste")
			(net "GND")
		)
	)
	(footprint ""
		(layer "F.Cu")
		(at 93.29801 -55.717694)
		(property "Reference" "C39"
			(at 0 0 0)
			(layer "F.SilkS")
			(hide yes)
			(effects
				(font
					(size 1.27 1.27)
				)
			)
		)
		(property "Value" ""
			(at 0 0 0)
			(layer "F.Fab")
			(effects
				(font
					(size 1.27 1.27)
				)
			)
		)
		(duplicate_pad_numbers_are_jumpers no)
		(fp_line
			(start -0.7874 -0.4064)
			(end 0.7874 -0.4064)
			(stroke
				(width 0.1524)
				(type default)
			)
			(layer "F.SilkS")
		)
		(fp_line
			(start -0.7874 0.4064)
			(end -0.7874 -0.4064)
			(stroke
				(width 0.1524)
				(type default)
			)
			(layer "F.SilkS")
		)
		(fp_line
			(start 0.7874 -0.4064)
			(end 0.7874 0.4064)
			(stroke
				(width 0.1524)
				(type default)
			)
			(layer "F.SilkS")
		)
		(fp_line
			(start 0.7874 0.4064)
			(end -0.7874 0.4064)
			(stroke
				(width 0.1524)
				(type default)
			)
			(layer "F.SilkS")
		)
		(fp_line
			(start -0.67945 -0.305054)
			(end -0.12065 -0.305054)
			(stroke
				(width 0.1)
				(type default)
			)
			(layer "F.Fab")
		)
		(fp_line
			(start -0.67945 0.3048)
			(end -0.67945 -0.305054)
			(stroke
				(width 0.1)
				(type default)
			)
			(layer "F.Fab")
		)
		(fp_line
			(start -0.12065 -0.305054)
			(end -0.12065 -0.2794)
			(stroke
				(width 0.1)
				(type default)
			)
			(layer "F.Fab")
		)
		(fp_line
			(start -0.12065 -0.2794)
			(end 0.12065 -0.2794)
			(stroke
				(width 0.1)
				(type default)
			)
			(layer "F.Fab")
		)
		(fp_line
			(start -0.12065 0.2794)
			(end -0.12065 0.3048)
			(stroke
				(width 0.1)
				(type default)
			)
			(layer "F.Fab")
		)
		(fp_line
			(start -0.12065 0.3048)
			(end -0.67945 0.3048)
			(stroke
				(width 0.1)
				(type default)
			)
			(layer "F.Fab")
		)
		(fp_line
			(start 0.120396 0.2794)
			(end -0.12065 0.2794)
			(stroke
				(width 0.1)
				(type default)
			)
			(layer "F.Fab")
		)
		(fp_line
			(start 0.120396 0.3048)
			(end 0.120396 0.2794)
			(stroke
				(width 0.1)
				(type default)
			)
			(layer "F.Fab")
		)
		(fp_line
			(start 0.12065 -0.3048)
			(end 0.67945 -0.3048)
			(stroke
				(width 0.1)
				(type default)
			)
			(layer "F.Fab")
		)
		(fp_line
			(start 0.12065 -0.2794)
			(end 0.12065 -0.3048)
			(stroke
				(width 0.1)
				(type default)
			)
			(layer "F.Fab")
		)
		(fp_line
			(start 0.67945 -0.3048)
			(end 0.67945 0.3048)
			(stroke
				(width 0.1)
				(type default)
			)
			(layer "F.Fab")
		)
		(fp_line
			(start 0.67945 0.3048)
			(end 0.120396 0.3048)
			(stroke
				(width 0.1)
				(type default)
			)
			(layer "F.Fab")
		)
		(pad "1" smd circle
			(at -0.40005 0)
			(size 0 0)
			(layers "F.Cu" "F.Mask" "F.Paste")
			(net "P3V3_OCP_VCC_2")
		)
		(pad "2" smd circle
			(at 0.40005 0)
			(size 0 0)
			(layers "F.Cu" "F.Mask" "F.Paste")
			(net "GND")
		)
	)
	(footprint ""
		(layer "F.Cu")
		(at 143.171672 -388.030974 90)
		(property "Reference" "R640"
			(at 0 0 90)
			(layer "F.SilkS")
			(hide yes)
			(effects
				(font
					(size 1.27 1.27)
				)
			)
		)
		(property "Value" ""
			(at 0 0 90)
			(layer "F.Fab")
			(effects
				(font
					(size 1.27 1.27)
				)
			)
		)
		(duplicate_pad_numbers_are_jumpers no)
		(fp_line
			(start 0.32512 -0.175006)
			(end 0.32512 0.175006)
			(stroke
				(width 0.1)
				(type default)
			)
			(layer "F.Fab")
		)
		(fp_line
			(start -0.32512 -0.175006)
			(end 0.32512 -0.175006)
			(stroke
				(width 0.1)
				(type default)
			)
			(layer "F.Fab")
		)
		(fp_line
			(start 0.32512 0.175006)
			(end -0.32512 0.175006)
			(stroke
				(width 0.1)
				(type default)
			)
			(layer "F.Fab")
		)
		(fp_line
			(start -0.32512 0.175006)
			(end -0.32512 -0.175006)
			(stroke
				(width 0.1)
				(type default)
			)
			(layer "F.Fab")
		)
		(pad "1" smd rect
			(at -0.2667 0 90)
			(size 0.3048 0.381)
			(layers "F.Cu" "F.Mask" "F.Paste")
			(net "CLK_100M_RETIMER_CPU1_P2_DP")
		)
		(pad "2" smd rect
			(at 0.2667 0 270)
			(size 0.3048 0.381)
			(layers "F.Cu" "F.Mask" "F.Paste")
			(net "GND")
		)
	)
	(footprint ""
		(layer "F.Cu")
		(at 239.53597 -291.863526 180)
		(property "Reference" "PC6518"
			(at 0 0 180)
			(layer "F.SilkS")
			(hide yes)
			(effects
				(font
					(size 1.27 1.27)
				)
			)
		)
		(property "Value" ""
			(at 0 0 180)
			(layer "F.Fab")
			(effects
				(font
					(size 1.27 1.27)
				)
			)
		)
		(duplicate_pad_numbers_are_jumpers no)
		(fp_line
			(start 0.7874 0.4064)
			(end -0.7874 0.4064)
			(stroke
				(width 0.1524)
				(type default)
			)
			(layer "F.SilkS")
		)
		(fp_line
			(start 0.7874 -0.4064)
			(end 0.7874 0.4064)
			(stroke
				(width 0.1524)
				(type default)
			)
			(layer "F.SilkS")
		)
		(fp_line
			(start -0.7874 0.4064)
			(end -0.7874 -0.4064)
			(stroke
				(width 0.1524)
				(type default)
			)
			(layer "F.SilkS")
		)
		(fp_line
			(start -0.7874 -0.4064)
			(end 0.7874 -0.4064)
			(stroke
				(width 0.1524)
				(type default)
			)
			(layer "F.SilkS")
		)
		(fp_line
			(start 0.67945 0.3048)
			(end 0.120396 0.3048)
			(stroke
				(width 0.1)
				(type default)
			)
			(layer "F.Fab")
		)
		(fp_line
			(start 0.67945 -0.3048)
			(end 0.67945 0.3048)
			(stroke
				(width 0.1)
				(type default)
			)
			(layer "F.Fab")
		)
		(fp_line
			(start 0.12065 -0.2794)
			(end 0.12065 -0.3048)
			(stroke
				(width 0.1)
				(type default)
			)
			(layer "F.Fab")
		)
		(fp_line
			(start 0.12065 -0.3048)
			(end 0.67945 -0.3048)
			(stroke
				(width 0.1)
				(type default)
			)
			(layer "F.Fab")
		)
		(fp_line
			(start 0.120396 0.3048)
			(end 0.120396 0.2794)
			(stroke
				(width 0.1)
				(type default)
			)
			(layer "F.Fab")
		)
		(fp_line
			(start 0.120396 0.2794)
			(end -0.12065 0.2794)
			(stroke
				(width 0.1)
				(type default)
			)
			(layer "F.Fab")
		)
		(fp_line
			(start -0.12065 0.3048)
			(end -0.67945 0.3048)
			(stroke
				(width 0.1)
				(type default)
			)
			(layer "F.Fab")
		)
		(fp_line
			(start -0.12065 0.2794)
			(end -0.12065 0.3048)
			(stroke
				(width 0.1)
				(type default)
			)
			(layer "F.Fab")
		)
		(fp_line
			(start -0.12065 -0.2794)
			(end 0.12065 -0.2794)
			(stroke
				(width 0.1)
				(type default)
			)
			(layer "F.Fab")
		)
		(fp_line
			(start -0.12065 -0.305054)
			(end -0.12065 -0.2794)
			(stroke
				(width 0.1)
				(type default)
			)
			(layer "F.Fab")
		)
		(fp_line
			(start -0.67945 0.3048)
			(end -0.67945 -0.305054)
			(stroke
				(width 0.1)
				(type default)
			)
			(layer "F.Fab")
		)
		(fp_line
			(start -0.67945 -0.305054)
			(end -0.12065 -0.305054)
			(stroke
				(width 0.1)
				(type default)
			)
			(layer "F.Fab")
		)
		(pad "1" smd circle
			(at -0.40005 0 180)
			(size 0 0)
			(layers "F.Cu" "F.Mask" "F.Paste")
			(net "P1V8_RETIMER_CPU0_REF")
		)
		(pad "2" smd circle
			(at 0.40005 0 180)
			(size 0 0)
			(layers "F.Cu" "F.Mask" "F.Paste")
			(net "GND")
		)
	)
	(footprint ""
		(layer "F.Cu")
		(at 460.204058 -52.196492 90)
		(property "Reference" "PC581"
			(at 0 0 90)
			(layer "F.SilkS")
			(hide yes)
			(effects
				(font
					(size 1.27 1.27)
				)
			)
		)
		(property "Value" ""
			(at 0 0 90)
			(layer "F.Fab")
			(effects
				(font
					(size 1.27 1.27)
				)
			)
		)
		(duplicate_pad_numbers_are_jumpers no)
		(fp_line
			(start 1.2954 -0.5842)
			(end 1.2954 0.5842)
			(stroke
				(width 0.1524)
				(type default)
			)
			(layer "F.SilkS")
		)
		(fp_line
			(start -1.2954 -0.5842)
			(end 1.2954 -0.5842)
			(stroke
				(width 0.1524)
				(type default)
			)
			(layer "F.SilkS")
		)
		(fp_line
			(start 1.2954 0.5842)
			(end -1.2954 0.5842)
			(stroke
				(width 0.1524)
				(type default)
			)
			(layer "F.SilkS")
		)
		(fp_line
			(start -1.2954 0.5842)
			(end -1.2954 -0.5842)
			(stroke
				(width 0.1524)
				(type default)
			)
			(layer "F.SilkS")
		)
		(fp_line
			(start 0.8636 -0.4572)
			(end 0.8636 -0.4064)
			(stroke
				(width 0.1)
				(type default)
			)
			(layer "F.Fab")
		)
		(fp_line
			(start -0.8636 -0.4572)
			(end 0.8636 -0.4572)
			(stroke
				(width 0.1)
				(type default)
			)
			(layer "F.Fab")
		)
		(fp_line
			(start 1.1938 -0.4064)
			(end 1.1938 0.4064)
			(stroke
				(width 0.1)
				(type default)
			)
			(layer "F.Fab")
		)
		(fp_line
			(start 0.8636 -0.4064)
			(end 1.1938 -0.4064)
			(stroke
				(width 0.1)
				(type default)
			)
			(layer "F.Fab")
		)
		(fp_line
			(start -0.8636 -0.4064)
			(end -0.8636 -0.4572)
			(stroke
				(width 0.1)
				(type default)
			)
			(layer "F.Fab")
		)
		(fp_line
			(start -1.1938 -0.4064)
			(end -0.8636 -0.4064)
			(stroke
				(width 0.1)
				(type default)
			)
			(layer "F.Fab")
		)
		(fp_line
			(start 1.1938 0.4064)
			(end 0.8636 0.4064)
			(stroke
				(width 0.1)
				(type default)
			)
			(layer "F.Fab")
		)
		(fp_line
			(start 0.8636 0.4064)
			(end 0.8636 0.4572)
			(stroke
				(width 0.1)
				(type default)
			)
			(layer "F.Fab")
		)
		(fp_line
			(start -0.8636 0.4064)
			(end -1.1938 0.4064)
			(stroke
				(width 0.1)
				(type default)
			)
			(layer "F.Fab")
		)
		(fp_line
			(start -1.1938 0.4064)
			(end -1.1938 -0.4064)
			(stroke
				(width 0.1)
				(type default)
			)
			(layer "F.Fab")
		)
		(fp_line
			(start 0.8636 0.4572)
			(end -0.8636 0.4572)
			(stroke
				(width 0.1)
				(type default)
			)
			(layer "F.Fab")
		)
		(fp_line
			(start -0.8636 0.4572)
			(end -0.8636 0.4064)
			(stroke
				(width 0.1)
				(type default)
			)
			(layer "F.Fab")
		)
		(pad "1" smd rect
			(at -0.7366 0)
			(size 0.7112 0.8128)
			(layers "F.Cu" "F.Mask" "F.Paste")
			(net "P3V3_AUX_VDRV")
		)
		(pad "2" smd rect
			(at 0.7366 0)
			(size 0.7112 0.8128)
			(layers "F.Cu" "F.Mask" "F.Paste")
			(net "GND")
		)
	)
	(footprint ""
		(layer "F.Cu")
		(at 319.22339 -192.09766 -90)
		(property "Reference" "R2311"
			(at 0 0 270)
			(layer "F.SilkS")
			(hide yes)
			(effects
				(font
					(size 1.27 1.27)
				)
			)
		)
		(property "Value" ""
			(at 0 0 270)
			(layer "F.Fab")
			(effects
				(font
					(size 1.27 1.27)
				)
			)
		)
		(duplicate_pad_numbers_are_jumpers no)
		(fp_line
			(start -0.7874 0.4064)
			(end -0.7874 -0.4064)
			(stroke
				(width 0.1524)
				(type default)
			)
			(layer "F.SilkS")
		)
		(fp_line
			(start 0.7874 0.4064)
			(end -0.7874 0.4064)
			(stroke
				(width 0.1524)
				(type default)
			)
			(layer "F.SilkS")
		)
		(fp_line
			(start -0.7874 -0.4064)
			(end 0.7874 -0.4064)
			(stroke
				(width 0.1524)
				(type default)
			)
			(layer "F.SilkS")
		)
		(fp_line
			(start 0.7874 -0.4064)
			(end 0.7874 0.4064)
			(stroke
				(width 0.1524)
				(type default)
			)
			(layer "F.SilkS")
		)
		(fp_line
			(start -0.67945 0.3048)
			(end -0.67945 -0.305054)
			(stroke
				(width 0.1)
				(type default)
			)
			(layer "F.Fab")
		)
		(fp_line
			(start -0.12065 0.3048)
			(end -0.67945 0.3048)
			(stroke
				(width 0.1)
				(type default)
			)
			(layer "F.Fab")
		)
		(fp_line
			(start 0.120396 0.3048)
			(end 0.120396 0.2794)
			(stroke
				(width 0.1)
				(type default)
			)
			(layer "F.Fab")
		)
		(fp_line
			(start 0.67945 0.3048)
			(end 0.120396 0.3048)
			(stroke
				(width 0.1)
				(type default)
			)
			(layer "F.Fab")
		)
		(fp_line
			(start -0.12065 0.2794)
			(end -0.12065 0.3048)
			(stroke
				(width 0.1)
				(type default)
			)
			(layer "F.Fab")
		)
		(fp_line
			(start 0.120396 0.2794)
			(end -0.12065 0.2794)
			(stroke
				(width 0.1)
				(type default)
			)
			(layer "F.Fab")
		)
		(fp_line
			(start -0.12065 -0.2794)
			(end 0.12065 -0.2794)
			(stroke
				(width 0.1)
				(type default)
			)
			(layer "F.Fab")
		)
		(fp_line
			(start 0.12065 -0.2794)
			(end 0.12065 -0.3048)
			(stroke
				(width 0.1)
				(type default)
			)
			(layer "F.Fab")
		)
		(fp_line
			(start 0.12065 -0.3048)
			(end 0.67945 -0.3048)
			(stroke
				(width 0.1)
				(type default)
			)
			(layer "F.Fab")
		)
		(fp_line
			(start 0.67945 -0.3048)
			(end 0.67945 0.3048)
			(stroke
				(width 0.1)
				(type default)
			)
			(layer "F.Fab")
		)
		(fp_line
			(start -0.67945 -0.305054)
			(end -0.12065 -0.305054)
			(stroke
				(width 0.1)
				(type default)
			)
			(layer "F.Fab")
		)
		(fp_line
			(start -0.12065 -0.305054)
			(end -0.12065 -0.2794)
			(stroke
				(width 0.1)
				(type default)
			)
			(layer "F.Fab")
		)
		(pad "1" smd rect
			(at -0.40005 0 90)
			(size 0.4572 0.508)
			(layers "F.Cu" "F.Mask" "F.Paste")
			(net "I3C_0_SPD_DDRAF_CPU0_R_SDA")
		)
		(pad "2" smd rect
			(at 0.40005 0 90)
			(size 0.4572 0.508)
			(layers "F.Cu" "F.Mask" "F.Paste")
			(net "I3C_SPD_DDRAF_CPU0_BYPASS_SDA")
		)
	)
)
